# BASEBOARD_FAB2 (Tioga Pass) — schematic netlist excerpt (pin names and nets, part order shuffled) for the footprints in the layout excerpt that follows; sources: Cadence DE-HDL packaged netlist, KiCad conversion of Wiwynn_Tioga_Pass_MB.brd

C8P14  CAP  100UF 4V 20% X5R  pkg 0805  page 76 : A = PVCCMCP_CPU1 ; B = GND
R2U2  RES  4.75K 1% CHIP  pkg 0402  page 156 : A = P3V3_STBY ; B = RST_PCH_SYSRST_BTN_OUT_N
C7U7  CAP  100UF 4V 20% X5R  pkg 0805  page 225 : A = PVDDQ_GHJ ; B = GND

(kicad_pcb
	(version 20260206)
	(generator "pcbnew")
	(generator_version "10.0")
	(general
		(thickness 1.6)
		(legacy_teardrops no)
	)
	(paper "A4")
	(title_block
		(title "Wiwynn_Tioga_Pass_MB.brd")
		(comment 1 "Tioga Pass / footprints 3843-3845 of 4770")
	)
	(layers
		(0 "F.Cu" signal "TOP")
		(4 "In1.Cu" signal "L2GND")
		(6 "In2.Cu" signal "L3")
		(8 "In3.Cu" signal "L4GND")
		(10 "In4.Cu" signal "L5")
		(12 "In5.Cu" signal "L6GND")
		(14 "In6.Cu" signal "L7VCC")
		(16 "In7.Cu" signal "L8VCC")
		(18 "In8.Cu" signal "L9GND")
		(20 "In9.Cu" signal "L10")
		(22 "In10.Cu" signal "L11GND")
		(24 "In11.Cu" signal "L12")
		(26 "In12.Cu" signal "L13GND")
		(2 "B.Cu" signal "BOTTOM")
		(9 "F.Adhes" user "F.Adhesive")
		(11 "B.Adhes" user "B.Adhesive")
		(13 "F.Paste" user "Package Geometry/Pastemask Top")
		(15 "B.Paste" user "Package Geometry/Pastemask Bottom")
		(5 "F.SilkS" user "Ref Des/Silkscreen Top")
		(7 "B.SilkS" user "Ref Des/Silkscreen Bottom")
		(1 "F.Mask" user "Board Geometry/Soldermask Top")
		(3 "B.Mask" user "Board Geometry/Soldermask Bottom")
		(17 "Dwgs.User" user "User.Drawings")
		(19 "Cmts.User" user "User.Comments")
		(21 "Eco1.User" user "User.Eco1")
		(23 "Eco2.User" user "User.Eco2")
		(25 "Edge.Cuts" user "Board Geometry/Outline")
		(27 "Margin" user)
		(31 "F.CrtYd" user "Package Geometry/Place Bound Top")
		(29 "B.CrtYd" user "Package Geometry/Place Bound Bottom")
		(35 "F.Fab" user "Ref Des/Assembly Top")
		(33 "B.Fab" user "Ref Des/Assembly Bottom")
	)
	(footprint ""
		(layer "B.Cu")
		(at 396.875 -37.846 180)
		(property "Reference" "R2U2"
			(at 0 0 0)
			(layer "B.SilkS")
			(hide yes)
			(effects
				(font
					(size 1.27 1.27)
				)
				(justify mirror)
			)
		)
		(property "Value" ""
			(at 0 0 0)
			(layer "B.Fab")
			(effects
				(font
					(size 1.27 1.27)
				)
				(justify mirror)
			)
		)
		(duplicate_pad_numbers_are_jumpers no)
		(fp_poly
			(pts
				(xy 0.2794 -0.1016) (xy -0.2794 -0.1016) (xy -0.2794 0.9906) (xy 0.2794 0.9906)
			)
			(stroke
				(width 0)
				(type default)
			)
			(fill no)
			(layer "B.CrtYd")
		)
		(fp_line
			(start 0.2794 0.9906)
			(end -0.2794 0.9906)
			(stroke
				(width 0.1)
				(type default)
			)
			(layer "B.Fab")
		)
		(fp_line
			(start 0.2794 -0.1016)
			(end 0.2794 0.9906)
			(stroke
				(width 0.1)
				(type default)
			)
			(layer "B.Fab")
		)
		(fp_line
			(start -0.2794 0.9906)
			(end -0.2794 -0.1016)
			(stroke
				(width 0.1)
				(type default)
			)
			(layer "B.Fab")
		)
		(fp_line
			(start -0.2794 -0.1016)
			(end 0.2794 -0.1016)
			(stroke
				(width 0.1)
				(type default)
			)
			(layer "B.Fab")
		)
		(pad "1" smd rect
			(at 0 0)
			(size 0.508 0.508)
			(layers "B.Cu" "B.Mask" "B.Paste")
			(net "P3V3_STBY")
		)
		(pad "2" smd rect
			(at 0 0.889)
			(size 0.508 0.508)
			(layers "B.Cu" "B.Mask" "B.Paste")
			(net "RST_PCH_SYSRST_BTN_OUT_N")
		)
		(zone
			(layer "B.Cu")
			(hatch none 0.5)
			(connect_pads
				(clearance 0)
			)
			(min_thickness 0.25)
			(keepout
				(tracks not_allowed)
				(vias allowed)
				(pads allowed)
				(copperpour not_allowed)
				(footprints allowed)
			)
			(placement
				(enabled no)
				(sheetname "")
			)
			(fill
				(thermal_gap 0.5)
				(thermal_bridge_width 0.5)
				(island_removal_mode 0)
			)
			(polygon
				(pts
					(xy 396.621 -38.481) (xy 397.129 -38.481) (xy 397.129 -38.1) (xy 396.621 -38.1)
				)
			)
		)
		(zone
			(layer "B.Cu")
			(hatch none 0.5)
			(connect_pads
				(clearance 0)
			)
			(min_thickness 0.25)
			(keepout
				(tracks allowed)
				(vias not_allowed)
				(pads allowed)
				(copperpour not_allowed)
				(footprints allowed)
			)
			(placement
				(enabled no)
				(sheetname "")
			)
			(fill
				(thermal_gap 0.5)
				(thermal_bridge_width 0.5)
				(island_removal_mode 0)
			)
			(polygon
				(pts
					(xy 396.621 -38.1) (xy 397.129 -38.1) (xy 397.129 -38.481) (xy 396.621 -38.481)
				)
			)
		)
	)
	(footprint ""
		(layer "B.Cu")
		(at 106.350054 -77.82814)
		(property "Reference" "C8P14"
			(at 0 0 0)
			(layer "B.SilkS")
			(hide yes)
			(effects
				(font
					(size 1.27 1.27)
				)
				(justify mirror)
			)
		)
		(property "Value" ""
			(at 0 0 0)
			(layer "B.Fab")
			(effects
				(font
					(size 1.27 1.27)
				)
				(justify mirror)
			)
		)
		(duplicate_pad_numbers_are_jumpers no)
		(fp_poly
			(pts
				(xy 0.7239 -0.2159) (xy -0.7239 -0.2159) (xy -0.7239 1.9939) (xy 0.7239 1.9939)
			)
			(stroke
				(width 0)
				(type default)
			)
			(fill no)
			(layer "B.CrtYd")
		)
		(fp_line
			(start -0.7239 -0.2159)
			(end 0.7239 -0.2159)
			(stroke
				(width 0.1)
				(type default)
			)
			(layer "B.Fab")
		)
		(fp_line
			(start -0.7239 1.9939)
			(end -0.7239 -0.2159)
			(stroke
				(width 0.1)
				(type default)
			)
			(layer "B.Fab")
		)
		(fp_line
			(start 0.7239 -0.2159)
			(end 0.7239 1.9939)
			(stroke
				(width 0.1)
				(type default)
			)
			(layer "B.Fab")
		)
		(fp_line
			(start 0.7239 1.9939)
			(end -0.7239 1.9939)
			(stroke
				(width 0.1)
				(type default)
			)
			(layer "B.Fab")
		)
		(pad "1" smd rect
			(at 0 0 180)
			(size 1.27 1.016)
			(layers "B.Cu" "B.Mask" "B.Paste")
			(net "PVCCMCP_CPU1")
		)
		(pad "2" smd rect
			(at 0 1.778 180)
			(size 1.27 1.016)
			(layers "B.Cu" "B.Mask" "B.Paste")
			(net "GND")
		)
		(zone
			(layer "B.Cu")
			(hatch none 0.5)
			(connect_pads
				(clearance 0)
			)
			(min_thickness 0.25)
			(keepout
				(tracks not_allowed)
				(vias allowed)
				(pads allowed)
				(copperpour not_allowed)
				(footprints allowed)
			)
			(placement
				(enabled no)
				(sheetname "")
			)
			(fill
				(thermal_gap 0.5)
				(thermal_bridge_width 0.5)
				(island_removal_mode 0)
			)
			(polygon
				(pts
					(xy 106.985054 -77.32014) (xy 105.715054 -77.32014) (xy 105.715054 -76.55814) (xy 106.985054 -76.55814)
				)
			)
		)
	)
	(footprint ""
		(layer "B.Cu")
		(at 109.065568 3.81 90)
		(property "Reference" "C7U7"
			(at 0 0 90)
			(layer "B.SilkS")
			(hide yes)
			(effects
				(font
					(size 1.27 1.27)
				)
				(justify mirror)
			)
		)
		(property "Value" ""
			(at 0 0 90)
			(layer "B.Fab")
			(effects
				(font
					(size 1.27 1.27)
				)
				(justify mirror)
			)
		)
		(duplicate_pad_numbers_are_jumpers no)
		(fp_poly
			(pts
				(xy 0.7239 -0.2159) (xy -0.7239 -0.2159) (xy -0.7239 1.9939) (xy 0.7239 1.9939)
			)
			(stroke
				(width 0)
				(type default)
			)
			(fill no)
			(layer "B.CrtYd")
		)
		(fp_line
			(start 0.7239 -0.2159)
			(end 0.7239 1.9939)
			(stroke
				(width 0.1)
				(type default)
			)
			(layer "B.Fab")
		)
		(fp_line
			(start -0.7239 -0.2159)
			(end 0.7239 -0.2159)
			(stroke
				(width 0.1)
				(type default)
			)
			(layer "B.Fab")
		)
		(fp_line
			(start 0.7239 1.9939)
			(end -0.7239 1.9939)
			(stroke
				(width 0.1)
				(type default)
			)
			(layer "B.Fab")
		)
		(fp_line
			(start -0.7239 1.9939)
			(end -0.7239 -0.2159)
			(stroke
				(width 0.1)
				(type default)
			)
			(layer "B.Fab")
		)
		(pad "1" smd rect
			(at 0 0 270)
			(size 1.27 1.016)
			(layers "B.Cu" "B.Mask" "B.Paste")
			(net "PVDDQ_GHJ")
		)
		(pad "2" smd rect
			(at 0 1.778 270)
			(size 1.27 1.016)
			(layers "B.Cu" "B.Mask" "B.Paste")
			(net "GND")
		)
		(zone
			(layer "B.Cu")
			(hatch none 0.5)
			(connect_pads
				(clearance 0)
			)
			(min_thickness 0.25)
			(keepout
				(tracks not_allowed)
				(vias allowed)
				(pads allowed)
				(copperpour not_allowed)
				(footprints allowed)
			)
			(placement
				(enabled no)
				(sheetname "")
			)
			(fill
				(thermal_gap 0.5)
				(thermal_bridge_width 0.5)
				(island_removal_mode 0)
			)
			(polygon
				(pts
					(xy 109.573568 3.175) (xy 109.573568 4.445) (xy 110.335568 4.445) (xy 110.335568 3.175)
				)
			)
		)
	)
)
